(kicad_pcb
	(version 20260206)
	(generator "pcbnew")
	(generator_version "10.0")
	(general
		(thickness 1.6)
		(legacy_teardrops no)
	)
	(paper "A4")
	(title_block
		(title "timecard-production-celestica-r4006 — R4006-B0001-02_R01.brd")
		(comment 1 "Time Appliance Project (Time Card) / footprints 39-42 of 1113")
	)
	(layers
		(0 "F.Cu" signal "TOP")
		(4 "In1.Cu" signal "L02_GND1")
		(6 "In2.Cu" signal "L03_SIG1")
		(8 "In3.Cu" signal "L04_GND2")
		(10 "In4.Cu" signal "L05_VCC1")
		(12 "In5.Cu" signal "L06_VCC2")
		(14 "In6.Cu" signal "L07_GND3")
		(16 "In7.Cu" signal "L08_SIG2")
		(18 "In8.Cu" signal "L09_GND4")
		(2 "B.Cu" signal "BOTTOM")
		(9 "F.Adhes" user "F.Adhesive")
		(11 "B.Adhes" user "B.Adhesive")
		(13 "F.Paste" user "Package Geometry/Pastemask Top")
		(15 "B.Paste" user "Package Geometry/Pastemask Bottom")
		(5 "F.SilkS" user "Ref Des/Silkscreen Top")
		(7 "B.SilkS" user "Ref Des/Silkscreen Bottom")
		(1 "F.Mask" user "Board Geometry/Soldermask Top")
		(3 "B.Mask" user "Board Geometry/Soldermask Bottom")
		(17 "Dwgs.User" user "User.Drawings")
		(19 "Cmts.User" user "User.Comments")
		(21 "Eco1.User" user "User.Eco1")
		(23 "Eco2.User" user "User.Eco2")
		(25 "Edge.Cuts" user "Board Geometry/Outline")
		(27 "Margin" user)
		(31 "F.CrtYd" user "Package Geometry/Place Bound Top")
		(29 "B.CrtYd" user "Package Geometry/Place Bound Bottom")
		(35 "F.Fab" user "Ref Des/Assembly Top")
		(33 "B.Fab" user "Ref Des/Assembly Bottom")
	)
	(footprint ""
		(layer "F.Cu")
		(at 23.5712 -65.544192 180)
		(property "Reference" "C276"
			(at -3.4798 -0.051562 0)
			(unlocked yes)
			(layer "F.SilkS")
			(effects
				(font
					(size 0.7874 0.5842)
					(thickness 0.1524)
				)
			)
		)
		(property "Value" "VAL*"
			(at 0.0762 2.067306 180)
			(unlocked yes)
			(layer "F.Fab")
			(hide yes)
			(effects
				(font
					(size 0.7874 0.5842)
					(thickness 0.1524)
				)
			)
		)
		(property "Tolerance" "TOL*"
			(at 0.0762 3.032506 180)
			(unlocked yes)
			(layer "Cmts.User")
			(hide yes)
			(effects
				(font
					(size 0.7874 0.5842)
					(thickness 0.1524)
				)
			)
		)
		(property "User Part Number" "PARTNUM*"
			(at 0.1016 4.023106 180)
			(unlocked yes)
			(layer "Cmts.User")
			(hide yes)
			(effects
				(font
					(size 0.7874 0.5842)
					(thickness 0.1524)
				)
			)
		)
		(property "Device Type" "CAPACITOR-G105-0B104-EK,0.1UF,A"
			(at 0.0508 1.127506 180)
			(unlocked yes)
			(layer "F.Fab")
			(hide yes)
			(effects
				(font
					(size 0.7874 0.5842)
					(thickness 0.1524)
				)
			)
		)
		(duplicate_pad_numbers_are_jumpers no)
		(fp_line
			(start 1.143 0.5588)
			(end 1.143 -0.5588)
			(stroke
				(width 0.1)
				(type default)
			)
			(layer "F.SilkS")
		)
		(fp_line
			(start 1.143 -0.5588)
			(end -1.143 -0.5588)
			(stroke
				(width 0.1)
				(type default)
			)
			(layer "F.SilkS")
		)
		(fp_line
			(start -1.143 0.5588)
			(end 1.143 0.5588)
			(stroke
				(width 0.1)
				(type default)
			)
			(layer "F.SilkS")
		)
		(fp_line
			(start -1.143 -0.5588)
			(end -1.143 0.5588)
			(stroke
				(width 0.1)
				(type default)
			)
			(layer "F.SilkS")
		)
		(fp_rect
			(start 1.143 0.5588)
			(end -1.143 -0.5588)
			(stroke
				(width 0)
				(type default)
			)
			(fill no)
			(layer "F.CrtYd")
		)
		(fp_line
			(start 0.508 0.3048)
			(end 0.508 -0.3048)
			(stroke
				(width 0.1)
				(type default)
			)
			(layer "F.Fab")
		)
		(fp_line
			(start 0.508 -0.3048)
			(end -0.508 -0.3048)
			(stroke
				(width 0.1)
				(type default)
			)
			(layer "F.Fab")
		)
		(fp_line
			(start -0.508 0.3048)
			(end 0.508 0.3048)
			(stroke
				(width 0.1)
				(type default)
			)
			(layer "F.Fab")
		)
		(fp_line
			(start -0.508 -0.3048)
			(end -0.508 0.3048)
			(stroke
				(width 0.1)
				(type default)
			)
			(layer "F.Fab")
		)
		(pad "1" smd rect
			(at -0.5334 0 180)
			(size 0.7112 0.6096)
			(layers "F.Cu" "F.Mask" "F.Paste")
			(net "XP1R8V_FPGA")
		)
		(pad "2" smd rect
			(at 0.5334 0 180)
			(size 0.7112 0.6096)
			(layers "F.Cu" "F.Mask" "F.Paste")
			(net "SG")
		)
		(zone
			(layer "F.Cu")
			(hatch none 0.5)
			(connect_pads
				(clearance 0)
			)
			(min_thickness 0.25)
			(keepout
				(tracks allowed)
				(vias not_allowed)
				(pads allowed)
				(copperpour not_allowed)
				(footprints allowed)
			)
			(placement
				(enabled no)
				(sheetname "")
			)
			(fill
				(thermal_gap 0.5)
				(thermal_bridge_width 0.5)
				(island_removal_mode 0)
			)
			(polygon
				(pts
					(xy 23.495 -65.848992) (xy 23.495 -65.239392) (xy 23.6474 -65.239392) (xy 23.6474 -65.848992)
				)
			)
		)
	)
	(footprint ""
		(layer "F.Cu")
		(at 6.1468 -68.201032 90)
		(property "Reference" "R374"
			(at 3.553968 -0.26543 90)
			(unlocked yes)
			(layer "F.SilkS")
			(effects
				(font
					(size 0.7874 0.5842)
					(thickness 0.1524)
				)
			)
		)
		(property "Value" "VAL*"
			(at 0.02032 2.13233 90)
			(unlocked yes)
			(layer "F.Fab")
			(hide yes)
			(effects
				(font
					(size 0.7874 0.5842)
					(thickness 0.1524)
				)
			)
		)
		(property "Device Type" "RESISTOR-G155-11000-01,100OHM,A"
			(at 0.008382 1.210564 90)
			(unlocked yes)
			(layer "F.Fab")
			(hide yes)
			(effects
				(font
					(size 0.7874 0.5842)
					(thickness 0.1524)
				)
			)
		)
		(property "User Part Number" "PARTNUM*"
			(at 0.02032 4.024884 90)
			(unlocked yes)
			(layer "Cmts.User")
			(hide yes)
			(effects
				(font
					(size 0.7874 0.5842)
					(thickness 0.1524)
				)
			)
		)
		(property "Tolerance" "TOL*"
			(at 0.044704 3.05435 90)
			(unlocked yes)
			(layer "Cmts.User")
			(hide yes)
			(effects
				(font
					(size 0.7874 0.5842)
					(thickness 0.1524)
				)
			)
		)
		(duplicate_pad_numbers_are_jumpers no)
		(fp_line
			(start 1.143 -0.5588)
			(end -1.143 -0.5588)
			(stroke
				(width 0.1)
				(type default)
			)
			(layer "F.SilkS")
		)
		(fp_line
			(start -1.143 -0.5588)
			(end -1.143 0.5588)
			(stroke
				(width 0.1)
				(type default)
			)
			(layer "F.SilkS")
		)
		(fp_line
			(start 1.143 0.5588)
			(end 1.143 -0.5588)
			(stroke
				(width 0.1)
				(type default)
			)
			(layer "F.SilkS")
		)
		(fp_line
			(start -1.143 0.5588)
			(end 1.143 0.5588)
			(stroke
				(width 0.1)
				(type default)
			)
			(layer "F.SilkS")
		)
		(fp_poly
			(pts
				(xy -1.143 0.5588) (xy 1.143 0.5588) (xy 1.143 -0.5588) (xy -1.143 -0.5588)
			)
			(stroke
				(width 0)
				(type default)
			)
			(fill no)
			(layer "F.CrtYd")
		)
		(fp_line
			(start 0.508 -0.3048)
			(end -0.508 -0.3048)
			(stroke
				(width 0.1)
				(type default)
			)
			(layer "F.Fab")
		)
		(fp_line
			(start -0.508 -0.3048)
			(end -0.508 0.3048)
			(stroke
				(width 0.1)
				(type default)
			)
			(layer "F.Fab")
		)
		(fp_line
			(start 0.508 0.3048)
			(end 0.508 -0.3048)
			(stroke
				(width 0.1)
				(type default)
			)
			(layer "F.Fab")
		)
		(fp_line
			(start -0.508 0.3048)
			(end 0.508 0.3048)
			(stroke
				(width 0.1)
				(type default)
			)
			(layer "F.Fab")
		)
		(pad "1" smd rect
			(at -0.5334 0 90)
			(size 0.7112 0.6096)
			(layers "F.Cu" "F.Mask" "F.Paste")
			(net "FPGA_OUT_SMA3_LED_BLUE_N")
		)
		(pad "2" smd rect
			(at 0.5334 0 90)
			(size 0.7112 0.6096)
			(layers "F.Cu" "F.Mask" "F.Paste")
			(net "UNNAMED_14_LED4PV14_I267_1")
		)
		(zone
			(layer "F.Cu")
			(hatch none 0.5)
			(connect_pads
				(clearance 0)
			)
			(min_thickness 0.25)
			(keepout
				(tracks allowed)
				(vias not_allowed)
				(pads allowed)
				(copperpour not_allowed)
				(footprints allowed)
			)
			(placement
				(enabled no)
				(sheetname "")
			)
			(fill
				(thermal_gap 0.5)
				(thermal_bridge_width 0.5)
				(island_removal_mode 0)
			)
			(polygon
				(pts
					(xy 6.4516 -68.124832) (xy 6.4516 -68.277232) (xy 5.842 -68.277232) (xy 5.842 -68.124832)
				)
			)
		)
		(zone
			(layer "F.Cu")
			(hatch none 0.5)
			(connect_pads
				(clearance 0)
			)
			(min_thickness 0.25)
			(keepout
				(tracks not_allowed)
				(vias allowed)
				(pads allowed)
				(copperpour not_allowed)
				(footprints allowed)
			)
			(placement
				(enabled no)
				(sheetname "")
			)
			(fill
				(thermal_gap 0.5)
				(thermal_bridge_width 0.5)
				(island_removal_mode 0)
			)
			(polygon
				(pts
					(xy 6.4516 -68.124832) (xy 6.4516 -68.277232) (xy 5.842 -68.277232) (xy 5.842 -68.124832)
				)
			)
		)
	)
	(footprint ""
		(layer "F.Cu")
		(at 5.969 -25.4 90)
		(property "Reference" "CR5"
			(at -0.508 2.32537 90)
			(unlocked yes)
			(layer "F.SilkS")
			(effects
				(font
					(size 0.7874 0.5842)
					(thickness 0.1524)
				)
			)
		)
		(property "Value" ""
			(at 0 0 90)
			(layer "F.Fab")
			(effects
				(font
					(size 1.27 1.27)
				)
			)
		)
		(property "User Part Number" "PARTNUM*"
			(at 0.254 3.718306 90)
			(unlocked yes)
			(layer "Cmts.User")
			(hide yes)
			(effects
				(font
					(size 0.7874 0.5842)
					(thickness 0.1524)
				)
			)
		)
		(property "Device Type" "DIODE_4_V1-G122-10123-01"
			(at 0.254 2.702306 90)
			(unlocked yes)
			(layer "F.Fab")
			(hide yes)
			(effects
				(font
					(size 0.7874 0.5842)
					(thickness 0.1524)
				)
			)
		)
		(duplicate_pad_numbers_are_jumpers no)
		(fp_line
			(start 2.0828 -1.7018)
			(end 2.0828 1.7018)
			(stroke
				(width 0.1)
				(type default)
			)
			(layer "F.SilkS")
		)
		(fp_line
			(start -2.0828 -1.7018)
			(end 2.0828 -1.7018)
			(stroke
				(width 0.1)
				(type default)
			)
			(layer "F.SilkS")
		)
		(fp_line
			(start 2.0828 1.7018)
			(end -2.0828 1.7018)
			(stroke
				(width 0.1)
				(type default)
			)
			(layer "F.SilkS")
		)
		(fp_line
			(start -2.0828 1.7018)
			(end -2.0828 -1.7018)
			(stroke
				(width 0.1)
				(type default)
			)
			(layer "F.SilkS")
		)
		(fp_poly
			(pts
				(arc
					(start -2.6162 -0.508)
					(mid -2.6162 -1.27)
					(end -2.6162 -0.508)
				)
			)
			(stroke
				(width 0)
				(type default)
			)
			(fill yes)
			(layer "F.SilkS")
		)
		(fp_rect
			(start -2.3368 -1.9304)
			(end 2.3368 1.9304)
			(stroke
				(width 0)
				(type default)
			)
			(fill no)
			(layer "F.CrtYd")
		)
		(fp_line
			(start 0.6477 -1.42875)
			(end 0.6477 1.42875)
			(stroke
				(width 0.1)
				(type default)
			)
			(layer "F.Fab")
		)
		(fp_line
			(start -0.6477 -1.42875)
			(end 0.6477 -1.42875)
			(stroke
				(width 0.1)
				(type default)
			)
			(layer "F.Fab")
		)
		(fp_line
			(start 1.143 -1.1811)
			(end 1.143 -0.7239)
			(stroke
				(width 0.1)
				(type default)
			)
			(layer "F.Fab")
		)
		(fp_line
			(start 0.6477 -1.1811)
			(end 1.143 -1.1811)
			(stroke
				(width 0.1)
				(type default)
			)
			(layer "F.Fab")
		)
		(fp_line
			(start -0.6477 -1.1811)
			(end -0.6477 -0.3175)
			(stroke
				(width 0.1)
				(type default)
			)
			(layer "F.Fab")
		)
		(fp_line
			(start -1.143 -1.1811)
			(end -0.6477 -1.1811)
			(stroke
				(width 0.1)
				(type default)
			)
			(layer "F.Fab")
		)
		(fp_line
			(start 1.143 -0.7239)
			(end 0.6477 -0.7239)
			(stroke
				(width 0.1)
				(type default)
			)
			(layer "F.Fab")
		)
		(fp_line
			(start 0.6477 -0.7239)
			(end 0.6477 -1.1811)
			(stroke
				(width 0.1)
				(type default)
			)
			(layer "F.Fab")
		)
		(fp_line
			(start -0.6477 -0.3175)
			(end -1.143 -0.3175)
			(stroke
				(width 0.1)
				(type default)
			)
			(layer "F.Fab")
		)
		(fp_line
			(start -1.143 -0.3175)
			(end -1.143 -1.1811)
			(stroke
				(width 0.1)
				(type default)
			)
			(layer "F.Fab")
		)
		(fp_line
			(start 1.143 0.7239)
			(end 1.143 1.1811)
			(stroke
				(width 0.1)
				(type default)
			)
			(layer "F.Fab")
		)
		(fp_line
			(start 0.6477 0.7239)
			(end 1.143 0.7239)
			(stroke
				(width 0.1)
				(type default)
			)
			(layer "F.Fab")
		)
		(fp_line
			(start -0.6477 0.7239)
			(end -0.6477 1.1811)
			(stroke
				(width 0.1)
				(type default)
			)
			(layer "F.Fab")
		)
		(fp_line
			(start -1.143 0.7239)
			(end -0.6477 0.7239)
			(stroke
				(width 0.1)
				(type default)
			)
			(layer "F.Fab")
		)
		(fp_line
			(start 1.143 1.1811)
			(end 0.6477 1.1811)
			(stroke
				(width 0.1)
				(type default)
			)
			(layer "F.Fab")
		)
		(fp_line
			(start 0.6477 1.1811)
			(end 0.6477 0.7239)
			(stroke
				(width 0.1)
				(type default)
			)
			(layer "F.Fab")
		)
		(fp_line
			(start -0.6477 1.1811)
			(end -1.143 1.1811)
			(stroke
				(width 0.1)
				(type default)
			)
			(layer "F.Fab")
		)
		(fp_line
			(start -1.143 1.1811)
			(end -1.143 0.7239)
			(stroke
				(width 0.1)
				(type default)
			)
			(layer "F.Fab")
		)
		(fp_line
			(start 0.6477 1.42875)
			(end -0.6477 1.42875)
			(stroke
				(width 0.1)
				(type default)
			)
			(layer "F.Fab")
		)
		(fp_line
			(start -0.6477 1.42875)
			(end -0.6477 -1.42875)
			(stroke
				(width 0.1)
				(type default)
			)
			(layer "F.Fab")
		)
		(fp_poly
			(pts
				(arc
					(start -0.381 -0.5588)
					(mid -0.381 -0.9398)
					(end -0.381 -0.5588)
				)
			)
			(stroke
				(width 0)
				(type default)
			)
			(fill yes)
			(layer "F.Fab")
		)
		(fp_text user "4"
			(at 2.510028 -1.311656 0)
			(unlocked yes)
			(layer "F.SilkS")
			(effects
				(font
					(size 0.635 0.4064)
					(thickness 0.1524)
				)
				(justify left)
			)
		)
		(fp_text user "3"
			(at 2.50825 1.4478 0)
			(unlocked yes)
			(layer "F.SilkS")
			(effects
				(font
					(size 0.635 0.4064)
					(thickness 0.1524)
				)
				(justify left)
			)
		)
		(fp_text user "2"
			(at -2.44475 1.8288 0)
			(unlocked yes)
			(layer "F.SilkS")
			(effects
				(font
					(size 0.635 0.4064)
					(thickness 0.1524)
				)
				(justify left)
			)
		)
		(fp_text user "4"
			(at 1.829308 -1.273556 0)
			(unlocked yes)
			(layer "F.Fab")
			(effects
				(font
					(size 0.7874 0.5842)
					(thickness 0.1524)
				)
				(justify left)
			)
		)
		(fp_text user "2"
			(at -1.81737 0.7239 0)
			(unlocked yes)
			(layer "F.Fab")
			(effects
				(font
					(size 0.7874 0.5842)
					(thickness 0.1524)
				)
				(justify left)
			)
		)
		(fp_text user "3"
			(at 1.829308 0.758444 0)
			(unlocked yes)
			(layer "F.Fab")
			(effects
				(font
					(size 0.7874 0.5842)
					(thickness 0.1524)
				)
				(justify left)
			)
		)
		(pad "1" smd rect
			(at -1.1049 -0.7493 90)
			(size 1.4478 1.0922)
			(layers "F.Cu" "F.Mask" "F.Paste")
			(net "SG")
		)
		(pad "2" smd rect
			(at -1.1049 0.9525 90)
			(size 1.4478 0.9906)
			(layers "F.Cu" "F.Mask" "F.Paste")
			(net "SMA4_SIG_IO_CONN")
		)
		(pad "3" smd rect
			(at 1.1049 0.9525 90)
			(size 1.4478 0.9906)
			(layers "F.Cu" "F.Mask" "F.Paste")
			(net "SMA3_SIG_IO_CONN")
		)
		(pad "4" smd rect
			(at 1.1049 -0.9525 90)
			(size 1.4478 0.9906)
			(layers "F.Cu" "F.Mask" "F.Paste")
			(net "Net_566")
		)
		(zone
			(layer "F.Cu")
			(hatch none 0.5)
			(connect_pads
				(clearance 0)
			)
			(min_thickness 0.25)
			(keepout
				(tracks allowed)
				(vias not_allowed)
				(pads allowed)
				(copperpour not_allowed)
				(footprints allowed)
			)
			(placement
				(enabled no)
				(sheetname "")
			)
			(fill
				(thermal_gap 0.5)
				(thermal_bridge_width 0.5)
				(island_removal_mode 0)
			)
			(polygon
				(pts
					(xy 4.6736 -24.7523) (xy 4.5339 -24.7523) (xy 4.5339 -25.781) (xy 5.5118 -25.781) (xy 5.5118 -26.0477)
					(xy 6.4262 -26.0477) (xy 6.4262 -25.781) (xy 7.4041 -25.781) (xy 7.4041 -25.019) (xy 6.4262 -25.019)
					(xy 6.4262 -24.7523) (xy 5.7658 -24.7523) (xy 5.7658 -25.019) (xy 4.6736 -25.019)
				)
			)
		)
	)
	(footprint ""
		(layer "F.Cu")
		(at 19.468338 -47.879 180)
		(property "Reference" "R396"
			(at -3.518662 -0.03937 0)
			(unlocked yes)
			(layer "F.SilkS")
			(effects
				(font
					(size 0.7874 0.5842)
					(thickness 0.1524)
				)
			)
		)
		(property "Value" "VAL*"
			(at 0.02032 2.13233 180)
			(unlocked yes)
			(layer "F.Fab")
			(hide yes)
			(effects
				(font
					(size 0.7874 0.5842)
					(thickness 0.1524)
				)
			)
		)
		(property "Tolerance" "TOL*"
			(at 0.044704 3.05435 180)
			(unlocked yes)
			(layer "Cmts.User")
			(hide yes)
			(effects
				(font
					(size 0.7874 0.5842)
					(thickness 0.1524)
				)
			)
		)
		(property "User Part Number" "PARTNUM*"
			(at 0.02032 4.024884 180)
			(unlocked yes)
			(layer "Cmts.User")
			(hide yes)
			(effects
				(font
					(size 0.7874 0.5842)
					(thickness 0.1524)
				)
			)
		)
		(property "Device Type" "RESISTOR-G155-133R0-01,33OHM,1%"
			(at 0.008382 1.210564 180)
			(unlocked yes)
			(layer "F.Fab")
			(hide yes)
			(effects
				(font
					(size 0.7874 0.5842)
					(thickness 0.1524)
				)
			)
		)
		(duplicate_pad_numbers_are_jumpers no)
		(fp_line
			(start 1.143 0.5588)
			(end 1.143 -0.5588)
			(stroke
				(width 0.1)
				(type default)
			)
			(layer "F.SilkS")
		)
		(fp_line
			(start 1.143 -0.5588)
			(end -1.143 -0.5588)
			(stroke
				(width 0.1)
				(type default)
			)
			(layer "F.SilkS")
		)
		(fp_line
			(start -1.143 0.5588)
			(end 1.143 0.5588)
			(stroke
				(width 0.1)
				(type default)
			)
			(layer "F.SilkS")
		)
		(fp_line
			(start -1.143 -0.5588)
			(end -1.143 0.5588)
			(stroke
				(width 0.1)
				(type default)
			)
			(layer "F.SilkS")
		)
		(fp_rect
			(start -1.143 -0.5588)
			(end 1.143 0.5588)
			(stroke
				(width 0)
				(type default)
			)
			(fill no)
			(layer "F.CrtYd")
		)
		(fp_line
			(start 0.508 0.3048)
			(end 0.508 -0.3048)
			(stroke
				(width 0.1)
				(type default)
			)
			(layer "F.Fab")
		)
		(fp_line
			(start 0.508 -0.3048)
			(end -0.508 -0.3048)
			(stroke
				(width 0.1)
				(type default)
			)
			(layer "F.Fab")
		)
		(fp_line
			(start -0.508 0.3048)
			(end 0.508 0.3048)
			(stroke
				(width 0.1)
				(type default)
			)
			(layer "F.Fab")
		)
		(fp_line
			(start -0.508 -0.3048)
			(end -0.508 0.3048)
			(stroke
				(width 0.1)
				(type default)
			)
			(layer "F.Fab")
		)
		(pad "1" smd rect
			(at -0.5334 0 180)
			(size 0.7112 0.6096)
			(layers "F.Cu" "F.Mask" "F.Paste")
			(net "SMA4_LED_RED_N")
		)
		(pad "2" smd rect
			(at 0.5334 0 180)
			(size 0.7112 0.6096)
			(layers "F.Cu" "F.Mask" "F.Paste")
			(net "UNNAMED_14_LED4PV14_I268_3")
		)
		(zone
			(layer "F.Cu")
			(hatch none 0.5)
			(connect_pads
				(clearance 0)
			)
			(min_thickness 0.25)
			(keepout
				(tracks not_allowed)
				(vias allowed)
				(pads allowed)
				(copperpour not_allowed)
				(footprints allowed)
			)
			(placement
				(enabled no)
				(sheetname "")
			)
			(fill
				(thermal_gap 0.5)
				(thermal_bridge_width 0.5)
				(island_removal_mode 0)
			)
			(polygon
				(pts
					(xy 19.544538 -47.5742) (xy 19.544538 -48.1838) (xy 19.392138 -48.1838) (xy 19.392138 -47.5742)
				)
			)
		)
		(zone
			(layer "F.Cu")
			(hatch none 0.5)
			(connect_pads
				(clearance 0)
			)
			(min_thickness 0.25)
			(keepout
				(tracks allowed)
				(vias not_allowed)
				(pads allowed)
				(copperpour not_allowed)
				(footprints allowed)
			)
			(placement
				(enabled no)
				(sheetname "")
			)
			(fill
				(thermal_gap 0.5)
				(thermal_bridge_width 0.5)
				(island_removal_mode 0)
			)
			(polygon
				(pts
					(xy 19.544538 -47.5742) (xy 19.544538 -48.1838) (xy 19.392138 -48.1838) (xy 19.392138 -47.5742)
				)
			)
		)
	)
)
